(kicad_pcb
	(version 20260206)
	(generator "pcbnew")
	(generator_version "10.0")
	(general
		(thickness 1.6)
		(legacy_teardrops no)
	)
	(paper "A4")
	(title_block
		(title "peb — Lightning_PEB_BRD.brd")
		(comment 1 "Lightning (Wiwynn / Facebook NVMe JBOF) / footprints 568-572 of 2563")
	)
	(layers
		(0 "F.Cu" signal "TOP")
		(4 "In1.Cu" signal "L2GND")
		(6 "In2.Cu" signal "L3")
		(8 "In3.Cu" signal "L4VCC")
		(10 "In4.Cu" signal "L5VCC")
		(12 "In5.Cu" signal "L6")
		(14 "In6.Cu" signal "L7GND")
		(2 "B.Cu" signal "BOTTOM")
		(9 "F.Adhes" user "F.Adhesive")
		(11 "B.Adhes" user "B.Adhesive")
		(13 "F.Paste" user "Package Geometry/Pastemask Top")
		(15 "B.Paste" user "Package Geometry/Pastemask Bottom")
		(5 "F.SilkS" user "Ref Des/Silkscreen Top")
		(7 "B.SilkS" user "Ref Des/Silkscreen Bottom")
		(1 "F.Mask" user "Board Geometry/Soldermask Top")
		(3 "B.Mask" user "Board Geometry/Soldermask Bottom")
		(17 "Dwgs.User" user "User.Drawings")
		(19 "Cmts.User" user "User.Comments")
		(21 "Eco1.User" user "User.Eco1")
		(23 "Eco2.User" user "User.Eco2")
		(25 "Edge.Cuts" user "Board Geometry/Outline")
		(27 "Margin" user)
		(31 "F.CrtYd" user "Package Geometry/Place Bound Top")
		(29 "B.CrtYd" user "Package Geometry/Place Bound Bottom")
		(35 "F.Fab" user "Ref Des/Assembly Top")
		(33 "B.Fab" user "Ref Des/Assembly Bottom")
	)
	(footprint ""
		(layer "F.Cu")
		(at 188.1124 -5.1562 -90)
		(property "Reference" "C269"
			(at 0 0 270)
			(layer "F.SilkS")
			(hide yes)
			(effects
				(font
					(size 1.27 1.27)
				)
			)
		)
		(property "Value" "SCD1U16V2KX-3GP"
			(at 1.1811 -2.7051 270)
			(unlocked yes)
			(layer "F.Fab")
			(hide yes)
			(effects
				(font
					(size 1.016 1.016)
					(thickness 0.1524)
				)
			)
		)
		(property "Device Type" "C402H22"
			(at 1.1811 -4.2291 270)
			(unlocked yes)
			(layer "F.Fab")
			(hide yes)
			(effects
				(font
					(size 1.016 1.016)
					(thickness 0.1524)
				)
			)
		)
		(duplicate_pad_numbers_are_jumpers no)
		(fp_rect
			(start -0.4318 0.9525)
			(end 0.4318 -0.9525)
			(stroke
				(width 0)
				(type default)
			)
			(fill no)
			(layer "F.CrtYd")
		)
		(fp_rect
			(start -0.4318 0.9525)
			(end 0.4318 -0.9525)
			(stroke
				(width 0)
				(type default)
			)
			(fill no)
			(layer "F.Fab")
		)
		(pad "1" smd custom
			(at 0 -0.4445 270)
			(size 0.1524 0.1524)
			(layers "F.Cu" "F.Mask" "F.Paste")
			(net "P3V3_STBY")
			(options
				(clearance outline)
				(anchor circle)
			)
			(primitives
				(gr_poly
					(pts
						(arc
							(start 0.3048 -0.2032)
							(mid 0.275042 -0.275042)
							(end 0.2032 -0.3048)
						)
						(arc
							(start -0.2032 -0.3048)
							(mid -0.275042 -0.275042)
							(end -0.3048 -0.2032)
						)
						(arc
							(start -0.3048 0.2032)
							(mid -0.275042 0.275042)
							(end -0.2032 0.3048)
						)
						(arc
							(start 0.2032 0.3048)
							(mid 0.275042 0.275042)
							(end 0.3048 0.2032)
						)
					)
					(width 0)
					(fill yes)
				)
			)
		)
		(pad "2" smd custom
			(at 0 0.4445 270)
			(size 0.1524 0.1524)
			(layers "F.Cu" "F.Mask" "F.Paste")
			(net "GND")
			(options
				(clearance outline)
				(anchor circle)
			)
			(primitives
				(gr_poly
					(pts
						(arc
							(start 0.3048 -0.2032)
							(mid 0.275042 -0.275042)
							(end 0.2032 -0.3048)
						)
						(arc
							(start -0.2032 -0.3048)
							(mid -0.275042 -0.275042)
							(end -0.3048 -0.2032)
						)
						(arc
							(start -0.3048 0.2032)
							(mid -0.275042 0.275042)
							(end -0.2032 0.3048)
						)
						(arc
							(start 0.2032 0.3048)
							(mid 0.275042 0.275042)
							(end 0.3048 0.2032)
						)
					)
					(width 0)
					(fill yes)
				)
			)
		)
	)
	(footprint ""
		(layer "F.Cu")
		(at 17.63268 -135.085074 90)
		(property "Reference" "R342"
			(at 0 0 90)
			(layer "F.SilkS")
			(hide yes)
			(effects
				(font
					(size 1.27 1.27)
				)
			)
		)
		(property "Value" "3K3R2F-2-GP"
			(at 0.064008 -3.993896 90)
			(unlocked yes)
			(layer "F.Fab")
			(hide yes)
			(effects
				(font
					(size 1.016 1.016)
					(thickness 0.1524)
				)
			)
		)
		(property "Device Type" "R402H16"
			(at 0.064008 -5.517896 90)
			(unlocked yes)
			(layer "F.Fab")
			(hide yes)
			(effects
				(font
					(size 1.016 1.016)
					(thickness 0.1524)
				)
			)
		)
		(duplicate_pad_numbers_are_jumpers no)
		(fp_line
			(start 0.508 -0.9398)
			(end -0.508 -0.9398)
			(stroke
				(width 0.1524)
				(type default)
			)
			(layer "F.SilkS")
		)
		(fp_line
			(start -0.508 -0.9398)
			(end -0.508 0.9398)
			(stroke
				(width 0.1524)
				(type default)
			)
			(layer "F.SilkS")
		)
		(fp_rect
			(start -0.508 0.9398)
			(end 0.508 -0.9398)
			(stroke
				(width 0)
				(type default)
			)
			(fill no)
			(layer "F.CrtYd")
		)
		(fp_rect
			(start -0.508 0.9398)
			(end 0.508 -0.9398)
			(stroke
				(width 0)
				(type default)
			)
			(fill no)
			(layer "F.Fab")
		)
		(pad "1" smd custom
			(at 0 -0.4445 90)
			(size 0.1397 0.1397)
			(layers "F.Cu" "F.Mask" "F.Paste")
			(net "P3V3_STBY")
			(options
				(clearance outline)
				(anchor circle)
			)
			(primitives
				(gr_poly
					(pts
						(arc
							(start -0.1778 -0.2794)
							(mid -0.249642 -0.249642)
							(end -0.2794 -0.1778)
						)
						(arc
							(start -0.2794 0.1778)
							(mid -0.249642 0.249642)
							(end -0.1778 0.2794)
						)
						(arc
							(start 0.1778 0.2794)
							(mid 0.249642 0.249642)
							(end 0.2794 0.1778)
						)
						(arc
							(start 0.2794 -0.1778)
							(mid 0.249642 -0.249642)
							(end 0.1778 -0.2794)
						)
					)
					(width 0)
					(fill yes)
				)
			)
		)
		(pad "2" smd custom
			(at 0 0.4445 90)
			(size 0.1397 0.1397)
			(layers "F.Cu" "F.Mask" "F.Paste")
			(net "ROMD0_R")
			(options
				(clearance outline)
				(anchor circle)
			)
			(primitives
				(gr_poly
					(pts
						(arc
							(start -0.1778 -0.2794)
							(mid -0.249642 -0.249642)
							(end -0.2794 -0.1778)
						)
						(arc
							(start -0.2794 0.1778)
							(mid -0.249642 0.249642)
							(end -0.1778 0.2794)
						)
						(arc
							(start 0.1778 0.2794)
							(mid 0.249642 0.249642)
							(end 0.2794 0.1778)
						)
						(arc
							(start 0.2794 -0.1778)
							(mid 0.249642 -0.249642)
							(end 0.1778 -0.2794)
						)
					)
					(width 0)
					(fill yes)
				)
			)
		)
	)
	(footprint ""
		(layer "F.Cu")
		(at 60.452 -35.433 -90)
		(property "Reference" "PR29"
			(at 0 0 270)
			(layer "F.SilkS")
			(hide yes)
			(effects
				(font
					(size 1.27 1.27)
				)
			)
		)
		(property "Value" "475KR2F-GP"
			(at 0.064008 -3.993896 270)
			(unlocked yes)
			(layer "F.Fab")
			(hide yes)
			(effects
				(font
					(size 1.016 1.016)
					(thickness 0.1524)
				)
			)
		)
		(property "Device Type" "R402H16"
			(at 0.064008 -5.517896 270)
			(unlocked yes)
			(layer "F.Fab")
			(hide yes)
			(effects
				(font
					(size 1.016 1.016)
					(thickness 0.1524)
				)
			)
		)
		(duplicate_pad_numbers_are_jumpers no)
		(fp_line
			(start -0.508 -0.9398)
			(end -0.508 0.9398)
			(stroke
				(width 0.1524)
				(type default)
			)
			(layer "F.SilkS")
		)
		(fp_line
			(start 0.508 -0.9398)
			(end -0.508 -0.9398)
			(stroke
				(width 0.1524)
				(type default)
			)
			(layer "F.SilkS")
		)
		(fp_rect
			(start -0.508 0.9398)
			(end 0.508 -0.9398)
			(stroke
				(width 0)
				(type default)
			)
			(fill no)
			(layer "F.CrtYd")
		)
		(fp_rect
			(start -0.508 0.9398)
			(end 0.508 -0.9398)
			(stroke
				(width 0)
				(type default)
			)
			(fill no)
			(layer "F.Fab")
		)
		(pad "1" smd custom
			(at 0 -0.4445 270)
			(size 0.1397 0.1397)
			(layers "F.Cu" "F.Mask" "F.Paste")
			(net "P3V3_STBY_MODE")
			(options
				(clearance outline)
				(anchor circle)
			)
			(primitives
				(gr_poly
					(pts
						(arc
							(start -0.1778 -0.2794)
							(mid -0.249642 -0.249642)
							(end -0.2794 -0.1778)
						)
						(arc
							(start -0.2794 0.1778)
							(mid -0.249642 0.249642)
							(end -0.1778 0.2794)
						)
						(arc
							(start 0.1778 0.2794)
							(mid 0.249642 0.249642)
							(end 0.2794 0.1778)
						)
						(arc
							(start 0.2794 -0.1778)
							(mid 0.249642 -0.249642)
							(end 0.1778 -0.2794)
						)
					)
					(width 0)
					(fill yes)
				)
			)
		)
		(pad "2" smd custom
			(at 0 0.4445 270)
			(size 0.1397 0.1397)
			(layers "F.Cu" "F.Mask" "F.Paste")
			(net "P3V3_STBY_PG")
			(options
				(clearance outline)
				(anchor circle)
			)
			(primitives
				(gr_poly
					(pts
						(arc
							(start -0.1778 -0.2794)
							(mid -0.249642 -0.249642)
							(end -0.2794 -0.1778)
						)
						(arc
							(start -0.2794 0.1778)
							(mid -0.249642 0.249642)
							(end -0.1778 0.2794)
						)
						(arc
							(start 0.1778 0.2794)
							(mid 0.249642 0.249642)
							(end 0.2794 0.1778)
						)
						(arc
							(start 0.2794 -0.1778)
							(mid 0.249642 -0.249642)
							(end 0.1778 -0.2794)
						)
					)
					(width 0)
					(fill yes)
				)
			)
		)
	)
	(footprint ""
		(layer "F.Cu")
		(at 155.408122 -212.420454 180)
		(property "Reference" "C251"
			(at 0 0 180)
			(layer "F.SilkS")
			(hide yes)
			(effects
				(font
					(size 1.27 1.27)
				)
			)
		)
		(property "Value" "SCD22U10V2KX-1GP"
			(at 1.1811 -2.7051 180)
			(unlocked yes)
			(layer "F.Fab")
			(hide yes)
			(effects
				(font
					(size 1.016 1.016)
					(thickness 0.1524)
				)
			)
		)
		(property "Device Type" "C402H22"
			(at 1.1811 -4.2291 180)
			(unlocked yes)
			(layer "F.Fab")
			(hide yes)
			(effects
				(font
					(size 1.016 1.016)
					(thickness 0.1524)
				)
			)
		)
		(duplicate_pad_numbers_are_jumpers no)
		(fp_rect
			(start -0.4318 0.9525)
			(end 0.4318 -0.9525)
			(stroke
				(width 0)
				(type default)
			)
			(fill no)
			(layer "F.CrtYd")
		)
		(fp_rect
			(start -0.4318 0.9525)
			(end 0.4318 -0.9525)
			(stroke
				(width 0)
				(type default)
			)
			(fill no)
			(layer "F.Fab")
		)
		(pad "1" smd custom
			(at 0 -0.4445 180)
			(size 0.1524 0.1524)
			(layers "F.Cu" "F.Mask" "F.Paste")
			(net "PCIE_TX_CAP_N54")
			(options
				(clearance outline)
				(anchor circle)
			)
			(primitives
				(gr_poly
					(pts
						(arc
							(start 0.3048 -0.2032)
							(mid 0.275042 -0.275042)
							(end 0.2032 -0.3048)
						)
						(arc
							(start -0.2032 -0.3048)
							(mid -0.275042 -0.275042)
							(end -0.3048 -0.2032)
						)
						(arc
							(start -0.3048 0.2032)
							(mid -0.275042 0.275042)
							(end -0.2032 0.3048)
						)
						(arc
							(start 0.2032 0.3048)
							(mid 0.275042 0.275042)
							(end 0.3048 0.2032)
						)
					)
					(width 0)
					(fill yes)
				)
			)
		)
		(pad "2" smd custom
			(at 0 0.4445 180)
			(size 0.1524 0.1524)
			(layers "F.Cu" "F.Mask" "F.Paste")
			(net "PCIE_TX_N54")
			(options
				(clearance outline)
				(anchor circle)
			)
			(primitives
				(gr_poly
					(pts
						(arc
							(start 0.3048 -0.2032)
							(mid 0.275042 -0.275042)
							(end 0.2032 -0.3048)
						)
						(arc
							(start -0.2032 -0.3048)
							(mid -0.275042 -0.275042)
							(end -0.3048 -0.2032)
						)
						(arc
							(start -0.3048 0.2032)
							(mid -0.275042 0.275042)
							(end -0.2032 0.3048)
						)
						(arc
							(start 0.2032 0.3048)
							(mid 0.275042 0.275042)
							(end 0.3048 0.2032)
						)
					)
					(width 0)
					(fill yes)
				)
			)
		)
	)
	(footprint ""
		(layer "F.Cu")
		(at 20.955 -137.7442 -90)
		(property "Reference" "R640"
			(at 0 0 270)
			(layer "F.SilkS")
			(hide yes)
			(effects
				(font
					(size 1.27 1.27)
				)
			)
		)
		(property "Value" "0R2J-2-GP"
			(at 0.064008 -3.993896 270)
			(unlocked yes)
			(layer "F.Fab")
			(hide yes)
			(effects
				(font
					(size 1.016 1.016)
					(thickness 0.1524)
				)
			)
		)
		(property "Device Type" "R402H16"
			(at 0.064008 -5.517896 270)
			(unlocked yes)
			(layer "F.Fab")
			(hide yes)
			(effects
				(font
					(size 1.016 1.016)
					(thickness 0.1524)
				)
			)
		)
		(duplicate_pad_numbers_are_jumpers no)
		(fp_line
			(start -0.508 -0.9398)
			(end -0.508 0.9398)
			(stroke
				(width 0.1524)
				(type default)
			)
			(layer "F.SilkS")
		)
		(fp_line
			(start 0.508 -0.9398)
			(end -0.508 -0.9398)
			(stroke
				(width 0.1524)
				(type default)
			)
			(layer "F.SilkS")
		)
		(fp_rect
			(start -0.508 0.9398)
			(end 0.508 -0.9398)
			(stroke
				(width 0)
				(type default)
			)
			(fill no)
			(layer "F.CrtYd")
		)
		(fp_rect
			(start -0.508 0.9398)
			(end 0.508 -0.9398)
			(stroke
				(width 0)
				(type default)
			)
			(fill no)
			(layer "F.Fab")
		)
		(pad "1" smd custom
			(at 0 -0.4445 270)
			(size 0.1397 0.1397)
			(layers "F.Cu" "F.Mask" "F.Paste")
			(net "GPIOR1_R")
			(options
				(clearance outline)
				(anchor circle)
			)
			(primitives
				(gr_poly
					(pts
						(arc
							(start -0.1778 -0.2794)
							(mid -0.249642 -0.249642)
							(end -0.2794 -0.1778)
						)
						(arc
							(start -0.2794 0.1778)
							(mid -0.249642 0.249642)
							(end -0.1778 0.2794)
						)
						(arc
							(start 0.1778 0.2794)
							(mid 0.249642 0.249642)
							(end 0.2794 0.1778)
						)
						(arc
							(start 0.2794 -0.1778)
							(mid 0.249642 -0.249642)
							(end 0.1778 -0.2794)
						)
					)
					(width 0)
					(fill yes)
				)
			)
		)
		(pad "2" smd custom
			(at 0 0.4445 270)
			(size 0.1397 0.1397)
			(layers "F.Cu" "F.Mask" "F.Paste")
			(net "TRAY_ID1")
			(options
				(clearance outline)
				(anchor circle)
			)
			(primitives
				(gr_poly
					(pts
						(arc
							(start -0.1778 -0.2794)
							(mid -0.249642 -0.249642)
							(end -0.2794 -0.1778)
						)
						(arc
							(start -0.2794 0.1778)
							(mid -0.249642 0.249642)
							(end -0.1778 0.2794)
						)
						(arc
							(start 0.1778 0.2794)
							(mid 0.249642 0.249642)
							(end 0.2794 0.1778)
						)
						(arc
							(start 0.2794 -0.1778)
							(mid 0.249642 -0.249642)
							(end 0.1778 -0.2794)
						)
					)
					(width 0)
					(fill yes)
				)
			)
		)
	)
)
